(kicad_pcb
	(version 20260206)
	(generator "pcbnew")
	(generator_version "10.0")
	(general
		(thickness 1.6)
		(legacy_teardrops no)
	)
	(paper "A4")
	(title_block
		(title "04192023_DAF0TMB3IC0_F0TG_MB_C_brd_V02_OCP.brd")
		(comment 1 "Grand Teton / footprints 7887-7893 of 8354")
	)
	(layers
		(0 "F.Cu" signal "TOP")
		(4 "In1.Cu" signal "GND")
		(6 "In2.Cu" signal "IN1")
		(8 "In3.Cu" signal "GND1")
		(10 "In4.Cu" signal "IN2")
		(12 "In5.Cu" signal "GND2")
		(14 "In6.Cu" signal "IN3")
		(16 "In7.Cu" signal "GND3")
		(18 "In8.Cu" signal "VCC")
		(20 "In9.Cu" signal "VCC1")
		(22 "In10.Cu" signal "GND4")
		(24 "In11.Cu" signal "IN4")
		(26 "In12.Cu" signal "GND5")
		(28 "In13.Cu" signal "IN5")
		(30 "In14.Cu" signal "GND6")
		(32 "In15.Cu" signal "IN6")
		(34 "In16.Cu" signal "GND7")
		(2 "B.Cu" signal "BOTTOM")
		(9 "F.Adhes" user "F.Adhesive")
		(11 "B.Adhes" user "B.Adhesive")
		(13 "F.Paste" user "Package Geometry/Pastemask Top")
		(15 "B.Paste" user "Package Geometry/Pastemask Bottom")
		(5 "F.SilkS" user "Ref Des/Silkscreen Top")
		(7 "B.SilkS" user "Ref Des/Silkscreen Bottom")
		(1 "F.Mask" user "Board Geometry/Soldermask Top")
		(3 "B.Mask" user "Board Geometry/Soldermask Bottom")
		(17 "Dwgs.User" user "User.Drawings")
		(19 "Cmts.User" user "User.Comments")
		(21 "Eco1.User" user "User.Eco1")
		(23 "Eco2.User" user "User.Eco2")
		(25 "Edge.Cuts" user "Board Geometry/Outline")
		(27 "Margin" user)
		(31 "F.CrtYd" user "Package Geometry/Place Bound Top")
		(29 "B.CrtYd" user "Package Geometry/Place Bound Bottom")
		(35 "F.Fab" user "Ref Des/Assembly Top")
		(33 "B.Fab" user "Ref Des/Assembly Bottom")
	)
	(footprint ""
		(layer "B.Cu")
		(at 405.086058 -319.748916 -90)
		(property "Reference" "R431"
			(at 0 0 90)
			(layer "B.SilkS")
			(hide yes)
			(effects
				(font
					(size 1.27 1.27)
				)
				(justify mirror)
			)
		)
		(property "Value" ""
			(at 0 0 90)
			(layer "B.Fab")
			(effects
				(font
					(size 1.27 1.27)
				)
				(justify mirror)
			)
		)
		(duplicate_pad_numbers_are_jumpers no)
		(fp_line
			(start -0.7874 0.4064)
			(end 0.7874 0.4064)
			(stroke
				(width 0.1524)
				(type default)
			)
			(layer "B.SilkS")
		)
		(fp_line
			(start 0.7874 0.4064)
			(end 0.7874 -0.4064)
			(stroke
				(width 0.1524)
				(type default)
			)
			(layer "B.SilkS")
		)
		(fp_line
			(start -0.7874 -0.4064)
			(end -0.7874 0.4064)
			(stroke
				(width 0.1524)
				(type default)
			)
			(layer "B.SilkS")
		)
		(fp_line
			(start 0.7874 -0.4064)
			(end -0.7874 -0.4064)
			(stroke
				(width 0.1524)
				(type default)
			)
			(layer "B.SilkS")
		)
		(fp_line
			(start -0.67945 0.3048)
			(end -0.120396 0.3048)
			(stroke
				(width 0.1)
				(type default)
			)
			(layer "B.Fab")
		)
		(fp_line
			(start -0.120396 0.3048)
			(end -0.120396 0.2794)
			(stroke
				(width 0.1)
				(type default)
			)
			(layer "B.Fab")
		)
		(fp_line
			(start 0.12065 0.3048)
			(end 0.67945 0.3048)
			(stroke
				(width 0.1)
				(type default)
			)
			(layer "B.Fab")
		)
		(fp_line
			(start 0.67945 0.3048)
			(end 0.67945 -0.305054)
			(stroke
				(width 0.1)
				(type default)
			)
			(layer "B.Fab")
		)
		(fp_line
			(start -0.120396 0.2794)
			(end 0.12065 0.2794)
			(stroke
				(width 0.1)
				(type default)
			)
			(layer "B.Fab")
		)
		(fp_line
			(start 0.12065 0.2794)
			(end 0.12065 0.3048)
			(stroke
				(width 0.1)
				(type default)
			)
			(layer "B.Fab")
		)
		(fp_line
			(start -0.12065 -0.2794)
			(end -0.12065 -0.3048)
			(stroke
				(width 0.1)
				(type default)
			)
			(layer "B.Fab")
		)
		(fp_line
			(start 0.12065 -0.2794)
			(end -0.12065 -0.2794)
			(stroke
				(width 0.1)
				(type default)
			)
			(layer "B.Fab")
		)
		(fp_line
			(start -0.67945 -0.3048)
			(end -0.67945 0.3048)
			(stroke
				(width 0.1)
				(type default)
			)
			(layer "B.Fab")
		)
		(fp_line
			(start -0.12065 -0.3048)
			(end -0.67945 -0.3048)
			(stroke
				(width 0.1)
				(type default)
			)
			(layer "B.Fab")
		)
		(fp_line
			(start 0.12065 -0.305054)
			(end 0.12065 -0.2794)
			(stroke
				(width 0.1)
				(type default)
			)
			(layer "B.Fab")
		)
		(fp_line
			(start 0.67945 -0.305054)
			(end 0.12065 -0.305054)
			(stroke
				(width 0.1)
				(type default)
			)
			(layer "B.Fab")
		)
		(pad "1" smd circle
			(at 0.40005 0 90)
			(size 0 0)
			(layers "B.Cu" "B.Mask" "B.Paste")
			(net "SMB_CPU0_4_R_SDA")
		)
		(pad "2" smd circle
			(at -0.40005 0 90)
			(size 0 0)
			(layers "B.Cu" "B.Mask" "B.Paste")
			(net "SMB_CPU0_4_SDA")
		)
	)
	(footprint ""
		(layer "B.Cu")
		(at 236.119162 -224.515934 -90)
		(property "Reference" "C23"
			(at 0 0 90)
			(layer "B.SilkS")
			(hide yes)
			(effects
				(font
					(size 1.27 1.27)
				)
				(justify mirror)
			)
		)
		(property "Value" ""
			(at 0 0 90)
			(layer "B.Fab")
			(effects
				(font
					(size 1.27 1.27)
				)
				(justify mirror)
			)
		)
		(duplicate_pad_numbers_are_jumpers no)
		(fp_line
			(start -0.7874 0.4064)
			(end 0.7874 0.4064)
			(stroke
				(width 0.1524)
				(type default)
			)
			(layer "B.SilkS")
		)
		(fp_line
			(start 0.7874 0.4064)
			(end 0.7874 -0.4064)
			(stroke
				(width 0.1524)
				(type default)
			)
			(layer "B.SilkS")
		)
		(fp_line
			(start -0.7874 -0.4064)
			(end -0.7874 0.4064)
			(stroke
				(width 0.1524)
				(type default)
			)
			(layer "B.SilkS")
		)
		(fp_line
			(start 0.7874 -0.4064)
			(end -0.7874 -0.4064)
			(stroke
				(width 0.1524)
				(type default)
			)
			(layer "B.SilkS")
		)
		(fp_line
			(start -0.67945 0.3048)
			(end -0.120396 0.3048)
			(stroke
				(width 0.1)
				(type default)
			)
			(layer "B.Fab")
		)
		(fp_line
			(start -0.120396 0.3048)
			(end -0.120396 0.2794)
			(stroke
				(width 0.1)
				(type default)
			)
			(layer "B.Fab")
		)
		(fp_line
			(start 0.12065 0.3048)
			(end 0.67945 0.3048)
			(stroke
				(width 0.1)
				(type default)
			)
			(layer "B.Fab")
		)
		(fp_line
			(start 0.67945 0.3048)
			(end 0.67945 -0.305054)
			(stroke
				(width 0.1)
				(type default)
			)
			(layer "B.Fab")
		)
		(fp_line
			(start -0.120396 0.2794)
			(end 0.12065 0.2794)
			(stroke
				(width 0.1)
				(type default)
			)
			(layer "B.Fab")
		)
		(fp_line
			(start 0.12065 0.2794)
			(end 0.12065 0.3048)
			(stroke
				(width 0.1)
				(type default)
			)
			(layer "B.Fab")
		)
		(fp_line
			(start -0.12065 -0.2794)
			(end -0.12065 -0.3048)
			(stroke
				(width 0.1)
				(type default)
			)
			(layer "B.Fab")
		)
		(fp_line
			(start 0.12065 -0.2794)
			(end -0.12065 -0.2794)
			(stroke
				(width 0.1)
				(type default)
			)
			(layer "B.Fab")
		)
		(fp_line
			(start -0.67945 -0.3048)
			(end -0.67945 0.3048)
			(stroke
				(width 0.1)
				(type default)
			)
			(layer "B.Fab")
		)
		(fp_line
			(start -0.12065 -0.3048)
			(end -0.67945 -0.3048)
			(stroke
				(width 0.1)
				(type default)
			)
			(layer "B.Fab")
		)
		(fp_line
			(start 0.12065 -0.305054)
			(end 0.12065 -0.2794)
			(stroke
				(width 0.1)
				(type default)
			)
			(layer "B.Fab")
		)
		(fp_line
			(start 0.67945 -0.305054)
			(end 0.12065 -0.305054)
			(stroke
				(width 0.1)
				(type default)
			)
			(layer "B.Fab")
		)
		(pad "1" smd circle
			(at 0.40005 0 90)
			(size 0 0)
			(layers "B.Cu" "B.Mask" "B.Paste")
			(net "P3V3_AUX")
		)
		(pad "2" smd circle
			(at -0.40005 0 90)
			(size 0 0)
			(layers "B.Cu" "B.Mask" "B.Paste")
			(net "GND")
		)
	)
	(footprint ""
		(layer "B.Cu")
		(at 95.837502 -205.14945 90)
		(property "Reference" "R531"
			(at 0 0 90)
			(layer "B.SilkS")
			(hide yes)
			(effects
				(font
					(size 1.27 1.27)
				)
				(justify mirror)
			)
		)
		(property "Value" ""
			(at 0 0 90)
			(layer "B.Fab")
			(effects
				(font
					(size 1.27 1.27)
				)
				(justify mirror)
			)
		)
		(duplicate_pad_numbers_are_jumpers no)
		(fp_line
			(start 0.7874 -0.4064)
			(end -0.7874 -0.4064)
			(stroke
				(width 0.1524)
				(type default)
			)
			(layer "B.SilkS")
		)
		(fp_line
			(start -0.7874 -0.4064)
			(end -0.7874 0.4064)
			(stroke
				(width 0.1524)
				(type default)
			)
			(layer "B.SilkS")
		)
		(fp_line
			(start 0.7874 0.4064)
			(end 0.7874 -0.4064)
			(stroke
				(width 0.1524)
				(type default)
			)
			(layer "B.SilkS")
		)
		(fp_line
			(start -0.7874 0.4064)
			(end 0.7874 0.4064)
			(stroke
				(width 0.1524)
				(type default)
			)
			(layer "B.SilkS")
		)
		(fp_line
			(start 0.67945 -0.305054)
			(end 0.12065 -0.305054)
			(stroke
				(width 0.1)
				(type default)
			)
			(layer "B.Fab")
		)
		(fp_line
			(start 0.12065 -0.305054)
			(end 0.12065 -0.2794)
			(stroke
				(width 0.1)
				(type default)
			)
			(layer "B.Fab")
		)
		(fp_line
			(start -0.12065 -0.3048)
			(end -0.67945 -0.3048)
			(stroke
				(width 0.1)
				(type default)
			)
			(layer "B.Fab")
		)
		(fp_line
			(start -0.67945 -0.3048)
			(end -0.67945 0.3048)
			(stroke
				(width 0.1)
				(type default)
			)
			(layer "B.Fab")
		)
		(fp_line
			(start 0.12065 -0.2794)
			(end -0.12065 -0.2794)
			(stroke
				(width 0.1)
				(type default)
			)
			(layer "B.Fab")
		)
		(fp_line
			(start -0.12065 -0.2794)
			(end -0.12065 -0.3048)
			(stroke
				(width 0.1)
				(type default)
			)
			(layer "B.Fab")
		)
		(fp_line
			(start 0.12065 0.2794)
			(end 0.12065 0.3048)
			(stroke
				(width 0.1)
				(type default)
			)
			(layer "B.Fab")
		)
		(fp_line
			(start -0.120396 0.2794)
			(end 0.12065 0.2794)
			(stroke
				(width 0.1)
				(type default)
			)
			(layer "B.Fab")
		)
		(fp_line
			(start 0.67945 0.3048)
			(end 0.67945 -0.305054)
			(stroke
				(width 0.1)
				(type default)
			)
			(layer "B.Fab")
		)
		(fp_line
			(start 0.12065 0.3048)
			(end 0.67945 0.3048)
			(stroke
				(width 0.1)
				(type default)
			)
			(layer "B.Fab")
		)
		(fp_line
			(start -0.120396 0.3048)
			(end -0.120396 0.2794)
			(stroke
				(width 0.1)
				(type default)
			)
			(layer "B.Fab")
		)
		(fp_line
			(start -0.67945 0.3048)
			(end -0.120396 0.3048)
			(stroke
				(width 0.1)
				(type default)
			)
			(layer "B.Fab")
		)
		(pad "1" smd circle
			(at 0.40005 0 270)
			(size 0 0)
			(layers "B.Cu" "B.Mask" "B.Paste")
			(net "CPU1_BP0")
		)
		(pad "2" smd circle
			(at -0.40005 0 270)
			(size 0 0)
			(layers "B.Cu" "B.Mask" "B.Paste")
			(net "PVDD18_S5_P1")
		)
	)
	(footprint ""
		(layer "B.Cu")
		(at 318.97828 -395.148562 90)
		(property "Reference" "C570"
			(at 0 0 90)
			(layer "B.SilkS")
			(hide yes)
			(effects
				(font
					(size 1.27 1.27)
				)
				(justify mirror)
			)
		)
		(property "Value" ""
			(at 0 0 90)
			(layer "B.Fab")
			(effects
				(font
					(size 1.27 1.27)
				)
				(justify mirror)
			)
		)
		(duplicate_pad_numbers_are_jumpers no)
		(fp_line
			(start 0.299974 -0.150114)
			(end -0.299974 -0.150114)
			(stroke
				(width 0.1)
				(type default)
			)
			(layer "B.Fab")
		)
		(fp_line
			(start -0.299974 -0.150114)
			(end -0.299974 0.150114)
			(stroke
				(width 0.1)
				(type default)
			)
			(layer "B.Fab")
		)
		(fp_line
			(start 0.299974 0.150114)
			(end 0.299974 -0.150114)
			(stroke
				(width 0.1)
				(type default)
			)
			(layer "B.Fab")
		)
		(fp_line
			(start -0.299974 0.150114)
			(end 0.299974 0.150114)
			(stroke
				(width 0.1)
				(type default)
			)
			(layer "B.Fab")
		)
		(pad "1" smd rect
			(at 0.2667 0 270)
			(size 0.3048 0.381)
			(layers "B.Cu" "B.Mask" "B.Paste")
			(net "P0V9_CPU0_RT0_2A")
		)
		(pad "2" smd rect
			(at -0.2667 0 270)
			(size 0.3048 0.381)
			(layers "B.Cu" "B.Mask" "B.Paste")
			(net "GND")
		)
	)
	(footprint ""
		(layer "B.Cu")
		(at 166.373048 -390.560052 90)
		(property "Reference" "C402"
			(at 0 0 90)
			(layer "B.SilkS")
			(hide yes)
			(effects
				(font
					(size 1.27 1.27)
				)
				(justify mirror)
			)
		)
		(property "Value" ""
			(at 0 0 90)
			(layer "B.Fab")
			(effects
				(font
					(size 1.27 1.27)
				)
				(justify mirror)
			)
		)
		(duplicate_pad_numbers_are_jumpers no)
		(fp_line
			(start 0.7874 -0.4064)
			(end -0.7874 -0.4064)
			(stroke
				(width 0.1524)
				(type default)
			)
			(layer "B.SilkS")
		)
		(fp_line
			(start -0.7874 -0.4064)
			(end -0.7874 0.4064)
			(stroke
				(width 0.1524)
				(type default)
			)
			(layer "B.SilkS")
		)
		(fp_line
			(start 0.7874 0.4064)
			(end 0.7874 -0.4064)
			(stroke
				(width 0.1524)
				(type default)
			)
			(layer "B.SilkS")
		)
		(fp_line
			(start -0.7874 0.4064)
			(end 0.7874 0.4064)
			(stroke
				(width 0.1524)
				(type default)
			)
			(layer "B.SilkS")
		)
		(fp_line
			(start 0.67945 -0.305054)
			(end 0.12065 -0.305054)
			(stroke
				(width 0.1)
				(type default)
			)
			(layer "B.Fab")
		)
		(fp_line
			(start 0.12065 -0.305054)
			(end 0.12065 -0.2794)
			(stroke
				(width 0.1)
				(type default)
			)
			(layer "B.Fab")
		)
		(fp_line
			(start -0.12065 -0.3048)
			(end -0.67945 -0.3048)
			(stroke
				(width 0.1)
				(type default)
			)
			(layer "B.Fab")
		)
		(fp_line
			(start -0.67945 -0.3048)
			(end -0.67945 0.3048)
			(stroke
				(width 0.1)
				(type default)
			)
			(layer "B.Fab")
		)
		(fp_line
			(start 0.12065 -0.2794)
			(end -0.12065 -0.2794)
			(stroke
				(width 0.1)
				(type default)
			)
			(layer "B.Fab")
		)
		(fp_line
			(start -0.12065 -0.2794)
			(end -0.12065 -0.3048)
			(stroke
				(width 0.1)
				(type default)
			)
			(layer "B.Fab")
		)
		(fp_line
			(start 0.12065 0.2794)
			(end 0.12065 0.3048)
			(stroke
				(width 0.1)
				(type default)
			)
			(layer "B.Fab")
		)
		(fp_line
			(start -0.120396 0.2794)
			(end 0.12065 0.2794)
			(stroke
				(width 0.1)
				(type default)
			)
			(layer "B.Fab")
		)
		(fp_line
			(start 0.67945 0.3048)
			(end 0.67945 -0.305054)
			(stroke
				(width 0.1)
				(type default)
			)
			(layer "B.Fab")
		)
		(fp_line
			(start 0.12065 0.3048)
			(end 0.67945 0.3048)
			(stroke
				(width 0.1)
				(type default)
			)
			(layer "B.Fab")
		)
		(fp_line
			(start -0.120396 0.3048)
			(end -0.120396 0.2794)
			(stroke
				(width 0.1)
				(type default)
			)
			(layer "B.Fab")
		)
		(fp_line
			(start -0.67945 0.3048)
			(end -0.120396 0.3048)
			(stroke
				(width 0.1)
				(type default)
			)
			(layer "B.Fab")
		)
		(pad "1" smd circle
			(at 0.40005 0 270)
			(size 0 0)
			(layers "B.Cu" "B.Mask" "B.Paste")
			(net "P0V9_CPU1_RT2_2A")
		)
		(pad "2" smd circle
			(at -0.40005 0 270)
			(size 0 0)
			(layers "B.Cu" "B.Mask" "B.Paste")
			(net "GND")
		)
	)
	(footprint ""
		(layer "B.Cu")
		(at 356.311454 -267.52931)
		(property "Reference" "C2227"
			(at 0 0 0)
			(layer "B.SilkS")
			(hide yes)
			(effects
				(font
					(size 1.27 1.27)
				)
				(justify mirror)
			)
		)
		(property "Value" ""
			(at 0 0 0)
			(layer "B.Fab")
			(effects
				(font
					(size 1.27 1.27)
				)
				(justify mirror)
			)
		)
		(duplicate_pad_numbers_are_jumpers no)
		(fp_line
			(start -0.7874 -0.4064)
			(end -0.7874 0.4064)
			(stroke
				(width 0.1524)
				(type default)
			)
			(layer "B.SilkS")
		)
		(fp_line
			(start -0.7874 0.4064)
			(end 0.7874 0.4064)
			(stroke
				(width 0.1524)
				(type default)
			)
			(layer "B.SilkS")
		)
		(fp_line
			(start 0.7874 -0.4064)
			(end -0.7874 -0.4064)
			(stroke
				(width 0.1524)
				(type default)
			)
			(layer "B.SilkS")
		)
		(fp_line
			(start 0.7874 0.4064)
			(end 0.7874 -0.4064)
			(stroke
				(width 0.1524)
				(type default)
			)
			(layer "B.SilkS")
		)
		(fp_line
			(start -0.67945 -0.3048)
			(end -0.67945 0.3048)
			(stroke
				(width 0.1)
				(type default)
			)
			(layer "B.Fab")
		)
		(fp_line
			(start -0.67945 0.3048)
			(end -0.120396 0.3048)
			(stroke
				(width 0.1)
				(type default)
			)
			(layer "B.Fab")
		)
		(fp_line
			(start -0.12065 -0.3048)
			(end -0.67945 -0.3048)
			(stroke
				(width 0.1)
				(type default)
			)
			(layer "B.Fab")
		)
		(fp_line
			(start -0.12065 -0.2794)
			(end -0.12065 -0.3048)
			(stroke
				(width 0.1)
				(type default)
			)
			(layer "B.Fab")
		)
		(fp_line
			(start -0.120396 0.2794)
			(end 0.12065 0.2794)
			(stroke
				(width 0.1)
				(type default)
			)
			(layer "B.Fab")
		)
		(fp_line
			(start -0.120396 0.3048)
			(end -0.120396 0.2794)
			(stroke
				(width 0.1)
				(type default)
			)
			(layer "B.Fab")
		)
		(fp_line
			(start 0.12065 -0.305054)
			(end 0.12065 -0.2794)
			(stroke
				(width 0.1)
				(type default)
			)
			(layer "B.Fab")
		)
		(fp_line
			(start 0.12065 -0.2794)
			(end -0.12065 -0.2794)
			(stroke
				(width 0.1)
				(type default)
			)
			(layer "B.Fab")
		)
		(fp_line
			(start 0.12065 0.2794)
			(end 0.12065 0.3048)
			(stroke
				(width 0.1)
				(type default)
			)
			(layer "B.Fab")
		)
		(fp_line
			(start 0.12065 0.3048)
			(end 0.67945 0.3048)
			(stroke
				(width 0.1)
				(type default)
			)
			(layer "B.Fab")
		)
		(fp_line
			(start 0.67945 -0.305054)
			(end 0.12065 -0.305054)
			(stroke
				(width 0.1)
				(type default)
			)
			(layer "B.Fab")
		)
		(fp_line
			(start 0.67945 0.3048)
			(end 0.67945 -0.305054)
			(stroke
				(width 0.1)
				(type default)
			)
			(layer "B.Fab")
		)
		(pad "1" smd circle
			(at 0.40005 0 180)
			(size 0 0)
			(layers "B.Cu" "B.Mask" "B.Paste")
			(net "PVDDCR_CPU1_P0")
		)
		(pad "2" smd circle
			(at -0.40005 0 180)
			(size 0 0)
			(layers "B.Cu" "B.Mask" "B.Paste")
			(net "GND")
		)
	)
	(footprint ""
		(layer "B.Cu")
		(at 358.057958 -248.916952 120)
		(property "Reference" "C2182"
			(at 0 0 120)
			(layer "B.SilkS")
			(hide yes)
			(effects
				(font
					(size 1.27 1.27)
				)
				(justify mirror)
			)
		)
		(property "Value" ""
			(at 0 0 120)
			(layer "B.Fab")
			(effects
				(font
					(size 1.27 1.27)
				)
				(justify mirror)
			)
		)
		(duplicate_pad_numbers_are_jumpers no)
		(fp_line
			(start 0.787516 -0.406438)
			(end -0.787425 -0.40652)
			(stroke
				(width 0.1524)
				(type default)
			)
			(layer "B.SilkS")
		)
		(fp_line
			(start 0.787425 0.40652)
			(end 0.787516 -0.406438)
			(stroke
				(width 0.1524)
				(type default)
			)
			(layer "B.SilkS")
		)
		(fp_line
			(start -0.787425 -0.40652)
			(end -0.787516 0.406438)
			(stroke
				(width 0.1524)
				(type default)
			)
			(layer "B.SilkS")
		)
		(fp_line
			(start -0.787516 0.406438)
			(end 0.787425 0.40652)
			(stroke
				(width 0.1524)
				(type default)
			)
			(layer "B.SilkS")
		)
		(fp_line
			(start 0.679475 -0.305158)
			(end 0.120732 -0.305125)
			(stroke
				(width 0.1)
				(type default)
			)
			(layer "B.Fab")
		)
		(fp_line
			(start 0.120732 -0.305125)
			(end 0.120554 -0.279418)
			(stroke
				(width 0.1)
				(type default)
			)
			(layer "B.Fab")
		)
		(fp_line
			(start 0.120554 -0.279418)
			(end -0.120587 -0.279326)
			(stroke
				(width 0.1)
				(type default)
			)
			(layer "B.Fab")
		)
		(fp_line
			(start -0.120536 -0.304813)
			(end -0.6795 -0.304908)
			(stroke
				(width 0.1)
				(type default)
			)
			(layer "B.Fab")
		)
		(fp_line
			(start -0.120587 -0.279326)
			(end -0.120536 -0.304813)
			(stroke
				(width 0.1)
				(type default)
			)
			(layer "B.Fab")
		)
		(fp_line
			(start 0.6795 0.304908)
			(end 0.679475 -0.305158)
			(stroke
				(width 0.1)
				(type default)
			)
			(layer "B.Fab")
		)
		(fp_line
			(start -0.6795 -0.304908)
			(end -0.679568 0.304811)
			(stroke
				(width 0.1)
				(type default)
			)
			(layer "B.Fab")
		)
		(fp_line
			(start 0.120587 0.279326)
			(end 0.120536 0.304813)
			(stroke
				(width 0.1)
				(type default)
			)
			(layer "B.Fab")
		)
		(fp_line
			(start 0.120536 0.304813)
			(end 0.6795 0.304908)
			(stroke
				(width 0.1)
				(type default)
			)
			(layer "B.Fab")
		)
		(fp_line
			(start -0.120334 0.279545)
			(end 0.120587 0.279326)
			(stroke
				(width 0.1)
				(type default)
			)
			(layer "B.Fab")
		)
		(fp_line
			(start -0.120258 0.304812)
			(end -0.120334 0.279545)
			(stroke
				(width 0.1)
				(type default)
			)
			(layer "B.Fab")
		)
		(fp_line
			(start -0.679568 0.304811)
			(end -0.120258 0.304812)
			(stroke
				(width 0.1)
				(type default)
			)
			(layer "B.Fab")
		)
		(pad "1" smd circle
			(at 0.40005 0 300)
			(size 0 0)
			(layers "B.Cu" "B.Mask" "B.Paste")
			(net "PVDDCR_CPU0_P0")
		)
		(pad "2" smd circle
			(at -0.40005 0 300)
			(size 0 0)
			(layers "B.Cu" "B.Mask" "B.Paste")
			(net "GND")
		)
	)
)
